# S9S_MB_2U (Grand Teton) — schematic netlist excerpt (pin names and nets, part order shuffled) for the footprints in the layout excerpt that follows; sources: Cadence DE-HDL packaged netlist, KiCad conversion of 03242023_DA0F0TMBIJ0_F0T_Motherboard_J_brd_V01_OCP.brd

C1272  Q_CAP  47UF 4V 20% X6S  pkg C0805  page 189 : A = P1V05_PCH_PLL_AUX ; B = GND
PC2  Q_CAP  22UF 4V 20% X6S  pkg C0805  page 297 : A = PVCCD_HV_CPU1 ; B = GND
R4280  Q_RES  1K 1% EMPTY  pkg 0402LF  page 169 : A = FM_USB3_1_FGA ; B = GND

(kicad_pcb
	(version 20260206)
	(generator "pcbnew")
	(generator_version "10.0")
	(general
		(thickness 1.6)
		(legacy_teardrops no)
	)
	(paper "A4")
	(title_block
		(title "03242023_DA0F0TMBIJ0_F0T_Motherboard_J_brd_V01_OCP.brd")
		(comment 1 "Grand Teton / footprints 4768-4770 of 6105")
	)
	(layers
		(0 "F.Cu" signal "TOP")
		(4 "In1.Cu" signal "GND")
		(6 "In2.Cu" signal "IN1")
		(8 "In3.Cu" signal "GND1")
		(10 "In4.Cu" signal "IN2")
		(12 "In5.Cu" signal "GND2")
		(14 "In6.Cu" signal "IN3")
		(16 "In7.Cu" signal "GND3")
		(18 "In8.Cu" signal "VCC")
		(20 "In9.Cu" signal "VCC1")
		(22 "In10.Cu" signal "GND4")
		(24 "In11.Cu" signal "IN4")
		(26 "In12.Cu" signal "GND5")
		(28 "In13.Cu" signal "IN5")
		(30 "In14.Cu" signal "GND6")
		(32 "In15.Cu" signal "IN6")
		(34 "In16.Cu" signal "GND7")
		(2 "B.Cu" signal "BOTTOM")
		(9 "F.Adhes" user "F.Adhesive")
		(11 "B.Adhes" user "B.Adhesive")
		(13 "F.Paste" user "Package Geometry/Pastemask Top")
		(15 "B.Paste" user "Package Geometry/Pastemask Bottom")
		(5 "F.SilkS" user "Ref Des/Silkscreen Top")
		(7 "B.SilkS" user "Ref Des/Silkscreen Bottom")
		(1 "F.Mask" user "Board Geometry/Soldermask Top")
		(3 "B.Mask" user "Board Geometry/Soldermask Bottom")
		(17 "Dwgs.User" user "User.Drawings")
		(19 "Cmts.User" user "User.Comments")
		(21 "Eco1.User" user "User.Eco1")
		(23 "Eco2.User" user "User.Eco2")
		(25 "Edge.Cuts" user "Board Geometry/Outline")
		(27 "Margin" user)
		(31 "F.CrtYd" user "Package Geometry/Place Bound Top")
		(29 "B.CrtYd" user "Package Geometry/Place Bound Bottom")
		(35 "F.Fab" user "Ref Des/Assembly Top")
		(33 "B.Fab" user "Ref Des/Assembly Bottom")
	)
	(footprint ""
		(layer "B.Cu")
		(at 128.85674 -20.996148 90)
		(property "Reference" "R4280"
			(at 0 0 90)
			(layer "B.SilkS")
			(hide yes)
			(effects
				(font
					(size 1.27 1.27)
				)
				(justify mirror)
			)
		)
		(property "Value" ""
			(at 0 0 90)
			(layer "B.Fab")
			(effects
				(font
					(size 1.27 1.27)
				)
				(justify mirror)
			)
		)
		(duplicate_pad_numbers_are_jumpers no)
		(fp_line
			(start 0.7874 -0.4064)
			(end -0.7874 -0.4064)
			(stroke
				(width 0.1524)
				(type default)
			)
			(layer "B.SilkS")
		)
		(fp_line
			(start -0.7874 -0.4064)
			(end -0.7874 0.4064)
			(stroke
				(width 0.1524)
				(type default)
			)
			(layer "B.SilkS")
		)
		(fp_line
			(start 0.7874 0.4064)
			(end 0.7874 -0.4064)
			(stroke
				(width 0.1524)
				(type default)
			)
			(layer "B.SilkS")
		)
		(fp_line
			(start -0.7874 0.4064)
			(end 0.7874 0.4064)
			(stroke
				(width 0.1524)
				(type default)
			)
			(layer "B.SilkS")
		)
		(fp_line
			(start 0.67945 -0.305054)
			(end 0.12065 -0.305054)
			(stroke
				(width 0.1)
				(type default)
			)
			(layer "B.Fab")
		)
		(fp_line
			(start 0.12065 -0.305054)
			(end 0.12065 -0.2794)
			(stroke
				(width 0.1)
				(type default)
			)
			(layer "B.Fab")
		)
		(fp_line
			(start -0.12065 -0.3048)
			(end -0.67945 -0.3048)
			(stroke
				(width 0.1)
				(type default)
			)
			(layer "B.Fab")
		)
		(fp_line
			(start -0.67945 -0.3048)
			(end -0.67945 0.3048)
			(stroke
				(width 0.1)
				(type default)
			)
			(layer "B.Fab")
		)
		(fp_line
			(start 0.12065 -0.2794)
			(end -0.12065 -0.2794)
			(stroke
				(width 0.1)
				(type default)
			)
			(layer "B.Fab")
		)
		(fp_line
			(start -0.12065 -0.2794)
			(end -0.12065 -0.3048)
			(stroke
				(width 0.1)
				(type default)
			)
			(layer "B.Fab")
		)
		(fp_line
			(start 0.12065 0.2794)
			(end 0.12065 0.3048)
			(stroke
				(width 0.1)
				(type default)
			)
			(layer "B.Fab")
		)
		(fp_line
			(start -0.120396 0.2794)
			(end 0.12065 0.2794)
			(stroke
				(width 0.1)
				(type default)
			)
			(layer "B.Fab")
		)
		(fp_line
			(start 0.67945 0.3048)
			(end 0.67945 -0.305054)
			(stroke
				(width 0.1)
				(type default)
			)
			(layer "B.Fab")
		)
		(fp_line
			(start 0.12065 0.3048)
			(end 0.67945 0.3048)
			(stroke
				(width 0.1)
				(type default)
			)
			(layer "B.Fab")
		)
		(fp_line
			(start -0.120396 0.3048)
			(end -0.120396 0.2794)
			(stroke
				(width 0.1)
				(type default)
			)
			(layer "B.Fab")
		)
		(fp_line
			(start -0.67945 0.3048)
			(end -0.120396 0.3048)
			(stroke
				(width 0.1)
				(type default)
			)
			(layer "B.Fab")
		)
		(pad "1" smd circle
			(at 0.40005 0 270)
			(size 0 0)
			(layers "B.Cu" "B.Mask" "B.Paste")
			(net "FM_USB3_1_FGA")
		)
		(pad "2" smd circle
			(at -0.40005 0 270)
			(size 0 0)
			(layers "B.Cu" "B.Mask" "B.Paste")
			(net "GND")
		)
	)
	(footprint ""
		(layer "B.Cu")
		(at 62.996572 -161.71926)
		(property "Reference" "PC2"
			(at 0 0 0)
			(layer "B.SilkS")
			(hide yes)
			(effects
				(font
					(size 1.27 1.27)
				)
				(justify mirror)
			)
		)
		(property "Value" ""
			(at 0 0 0)
			(layer "B.Fab")
			(effects
				(font
					(size 1.27 1.27)
				)
				(justify mirror)
			)
		)
		(duplicate_pad_numbers_are_jumpers no)
		(fp_line
			(start -1.524 -0.762)
			(end -1.524 0.762)
			(stroke
				(width 0.1524)
				(type default)
			)
			(layer "B.SilkS")
		)
		(fp_line
			(start -1.524 0.762)
			(end 1.524 0.762)
			(stroke
				(width 0.1524)
				(type default)
			)
			(layer "B.SilkS")
		)
		(fp_line
			(start 1.524 -0.762)
			(end -1.524 -0.762)
			(stroke
				(width 0.1524)
				(type default)
			)
			(layer "B.SilkS")
		)
		(fp_line
			(start 1.524 0.762)
			(end 1.524 -0.762)
			(stroke
				(width 0.1524)
				(type default)
			)
			(layer "B.SilkS")
		)
		(fp_line
			(start -1.1049 -0.724916)
			(end 1.1049 -0.724916)
			(stroke
				(width 0.1)
				(type default)
			)
			(layer "B.Fab")
		)
		(fp_line
			(start -1.1049 0.724916)
			(end -1.1049 -0.724916)
			(stroke
				(width 0.1)
				(type default)
			)
			(layer "B.Fab")
		)
		(fp_line
			(start 1.1049 -0.724916)
			(end 1.1049 0.724916)
			(stroke
				(width 0.1)
				(type default)
			)
			(layer "B.Fab")
		)
		(fp_line
			(start 1.1049 0.724916)
			(end -1.1049 0.724916)
			(stroke
				(width 0.1)
				(type default)
			)
			(layer "B.Fab")
		)
		(pad "1" smd rect
			(at 0.889 0)
			(size 1.016 1.27)
			(layers "B.Cu" "B.Mask" "B.Paste")
			(net "PVCCD_HV_CPU1")
		)
		(pad "2" smd rect
			(at -0.889 0)
			(size 1.016 1.27)
			(layers "B.Cu" "B.Mask" "B.Paste")
			(net "GND")
		)
	)
	(footprint ""
		(layer "B.Cu")
		(at 332.657196 -61.821314 45)
		(property "Reference" "C1272"
			(at 0 0 45)
			(layer "B.SilkS")
			(hide yes)
			(effects
				(font
					(size 1.27 1.27)
				)
				(justify mirror)
			)
		)
		(property "Value" ""
			(at 0 0 45)
			(layer "B.Fab")
			(effects
				(font
					(size 1.27 1.27)
				)
				(justify mirror)
			)
		)
		(duplicate_pad_numbers_are_jumpers no)
		(fp_line
			(start -1.523949 -0.762065)
			(end -1.523949 0.762065)
			(stroke
				(width 0.1524)
				(type default)
			)
			(layer "B.SilkS")
		)
		(fp_line
			(start -1.523949 0.762065)
			(end 1.523949 0.762065)
			(stroke
				(width 0.1524)
				(type default)
			)
			(layer "B.SilkS")
		)
		(fp_line
			(start 1.523949 -0.762065)
			(end -1.523949 -0.762065)
			(stroke
				(width 0.1524)
				(type default)
			)
			(layer "B.SilkS")
		)
		(fp_line
			(start 1.523949 0.762065)
			(end 1.523949 -0.762065)
			(stroke
				(width 0.1524)
				(type default)
			)
			(layer "B.SilkS")
		)
		(fp_line
			(start -1.104931 -0.724886)
			(end 1.104931 -0.724886)
			(stroke
				(width 0.1)
				(type default)
			)
			(layer "B.Fab")
		)
		(fp_line
			(start -1.104931 0.724886)
			(end -1.104931 -0.724886)
			(stroke
				(width 0.1)
				(type default)
			)
			(layer "B.Fab")
		)
		(fp_line
			(start 1.104931 -0.724886)
			(end 1.104931 0.724886)
			(stroke
				(width 0.1)
				(type default)
			)
			(layer "B.Fab")
		)
		(fp_line
			(start 1.104931 0.724886)
			(end -1.104931 0.724886)
			(stroke
				(width 0.1)
				(type default)
			)
			(layer "B.Fab")
		)
		(pad "1" smd rect
			(at 0.889 0 45)
			(size 1.016 1.27)
			(layers "B.Cu" "B.Mask" "B.Paste")
			(net "P1V05_PCH_PLL_AUX")
		)
		(pad "2" smd rect
			(at -0.889 0 45)
			(size 1.016 1.27)
			(layers "B.Cu" "B.Mask" "B.Paste")
			(net "GND")
		)
	)
)
